# BASEBOARD_FAB2 (Tioga Pass) — schematic netlist excerpt (pin names and nets, part order shuffled) for the footprints in the layout excerpt that follows; sources: Cadence DE-HDL packaged netlist, KiCad conversion of Wiwynn_Tioga_Pass_MB.brd

U32W1  TCA9517DGKR-GP  pkg DISCRET-G8  page 185
  VCCA  = P1V8_M2
  SCLA  = SMB_M2_SCL_R
  SDAA  = SMB_M2_SDA_R
  GND  = GND
  EN  = PD_SMB_M2_EN
  SDAB  = SMB_OCP_LAN_STBY_LVC3_SDA
  SCLB  = SMB_OCP_LAN_STBY_LVC3_SCL
  VCCB  = P3V3_STBY

C2M6  CAP_A  1.0UF 6.3V 10% X6S  pkg 0402V  page 127 : A = P1V05_PCH_STBY ; B = GND

(kicad_pcb
	(version 20260206)
	(generator "pcbnew")
	(generator_version "10.0")
	(general
		(thickness 1.6)
		(legacy_teardrops no)
	)
	(paper "A4")
	(title_block
		(title "Wiwynn_Tioga_Pass_MB.brd")
		(comment 1 "Tioga Pass / footprints 3858-3859 of 4770")
	)
	(layers
		(0 "F.Cu" signal "TOP")
		(4 "In1.Cu" signal "L2GND")
		(6 "In2.Cu" signal "L3")
		(8 "In3.Cu" signal "L4GND")
		(10 "In4.Cu" signal "L5")
		(12 "In5.Cu" signal "L6GND")
		(14 "In6.Cu" signal "L7VCC")
		(16 "In7.Cu" signal "L8VCC")
		(18 "In8.Cu" signal "L9GND")
		(20 "In9.Cu" signal "L10")
		(22 "In10.Cu" signal "L11GND")
		(24 "In11.Cu" signal "L12")
		(26 "In12.Cu" signal "L13GND")
		(2 "B.Cu" signal "BOTTOM")
		(9 "F.Adhes" user "F.Adhesive")
		(11 "B.Adhes" user "B.Adhesive")
		(13 "F.Paste" user "Package Geometry/Pastemask Top")
		(15 "B.Paste" user "Package Geometry/Pastemask Bottom")
		(5 "F.SilkS" user "Ref Des/Silkscreen Top")
		(7 "B.SilkS" user "Ref Des/Silkscreen Bottom")
		(1 "F.Mask" user "Board Geometry/Soldermask Top")
		(3 "B.Mask" user "Board Geometry/Soldermask Bottom")
		(17 "Dwgs.User" user "User.Drawings")
		(19 "Cmts.User" user "User.Comments")
		(21 "Eco1.User" user "User.Eco1")
		(23 "Eco2.User" user "User.Eco2")
		(25 "Edge.Cuts" user "Board Geometry/Outline")
		(27 "Margin" user)
		(31 "F.CrtYd" user "Package Geometry/Place Bound Top")
		(29 "B.CrtYd" user "Package Geometry/Place Bound Bottom")
		(35 "F.Fab" user "Ref Des/Assembly Top")
		(33 "B.Fab" user "Ref Des/Assembly Bottom")
	)
	(footprint ""
		(layer "B.Cu")
		(at 393.005818 -14.637004)
		(property "Reference" "U32W1"
			(at 0 0 0)
			(layer "B.SilkS")
			(hide yes)
			(effects
				(font
					(size 1.27 1.27)
				)
				(justify mirror)
			)
		)
		(property "Value" "*"
			(at 0.1143 -9.3091 0)
			(unlocked yes)
			(layer "B.Fab")
			(hide yes)
			(effects
				(font
					(size 1.27 1.016)
					(thickness 0.1524)
				)
				(justify mirror)
			)
		)
		(property "Device Type" "TCA9517DGKR-GP_DISCRET-G8-TCA9A"
			(at 0.1143 -10.9093 0)
			(unlocked yes)
			(layer "B.Fab")
			(hide yes)
			(effects
				(font
					(size 1.27 1.016)
					(thickness 0.1524)
				)
				(justify mirror)
			)
		)
		(duplicate_pad_numbers_are_jumpers no)
		(fp_line
			(start -1.0795 -1.016)
			(end 1.9558 -1.016)
			(stroke
				(width 0.1524)
				(type default)
			)
			(layer "B.SilkS")
		)
		(fp_line
			(start -1.0795 1.016)
			(end -1.0795 -1.016)
			(stroke
				(width 0.1524)
				(type default)
			)
			(layer "B.SilkS")
		)
		(fp_line
			(start 1.4478 -0.0381)
			(end 1.9558 0.4699)
			(stroke
				(width 0.1524)
				(type default)
			)
			(layer "B.SilkS")
		)
		(fp_line
			(start 1.778 1.0922)
			(end 1.778 3.048)
			(stroke
				(width 0.508)
				(type default)
			)
			(layer "B.SilkS")
		)
		(fp_line
			(start 1.9558 -1.016)
			(end 1.9558 1.016)
			(stroke
				(width 0.1524)
				(type default)
			)
			(layer "B.SilkS")
		)
		(fp_line
			(start 1.9558 -0.5461)
			(end 1.4478 -0.0381)
			(stroke
				(width 0.1524)
				(type default)
			)
			(layer "B.SilkS")
		)
		(fp_line
			(start 1.9558 1.016)
			(end -1.0795 1.016)
			(stroke
				(width 0.1524)
				(type default)
			)
			(layer "B.SilkS")
		)
		(fp_poly
			(pts
				(xy 1.1557 -1.016) (xy 1.1557 1.016) (xy -1.1557 1.016) (xy -1.1557 -1.016)
			)
			(stroke
				(width 0)
				(type default)
			)
			(fill yes)
			(layer "B.SilkS")
		)
		(fp_rect
			(start 1.4986 2.4511)
			(end -1.4986 -2.4511)
			(stroke
				(width 0)
				(type default)
			)
			(fill no)
			(layer "B.CrtYd")
		)
		(fp_poly
			(pts
				(xy 2.032 3.302) (xy 2.032 -3.302) (xy -2.032 -3.302) (xy -2.032 -2.1209) (xy -1.4986 -2.1209) (xy -1.4986 -2.4511)
				(xy 1.4986 -2.4511) (xy 1.4986 2.4511) (xy -1.4986 2.4511) (xy -1.4986 -2.1082) (xy -2.032 -2.1082)
				(xy -2.032 3.302)
			)
			(stroke
				(width 0)
				(type default)
			)
			(fill no)
			(layer "B.CrtYd")
		)
		(fp_rect
			(start 2.032 3.302)
			(end -2.032 -3.302)
			(stroke
				(width 0)
				(type default)
			)
			(fill no)
			(layer "B.Fab")
		)
		(pad "1" smd rect
			(at 0.97536 2.05486 180)
			(size 0.3556 1.524)
			(layers "B.Cu" "B.Mask" "B.Paste")
			(net "P1V8_M2")
		)
		(pad "2" smd rect
			(at 0.32512 2.05486 180)
			(size 0.3556 1.524)
			(layers "B.Cu" "B.Mask" "B.Paste")
			(net "SMB_M2_SCL_R")
		)
		(pad "3" smd rect
			(at -0.32512 2.05486 180)
			(size 0.3556 1.524)
			(layers "B.Cu" "B.Mask" "B.Paste")
			(net "SMB_M2_SDA_R")
		)
		(pad "4" smd rect
			(at -0.97536 2.05486 180)
			(size 0.3556 1.524)
			(layers "B.Cu" "B.Mask" "B.Paste")
			(net "GND")
		)
		(pad "5" smd rect
			(at -0.97536 -2.05486 180)
			(size 0.3556 1.524)
			(layers "B.Cu" "B.Mask" "B.Paste")
			(net "PD_SMB_M2_EN")
		)
		(pad "6" smd rect
			(at -0.32512 -2.05486 180)
			(size 0.3556 1.524)
			(layers "B.Cu" "B.Mask" "B.Paste")
			(net "SMB_OCP_LAN_STBY_LVC3_SDA")
		)
		(pad "7" smd rect
			(at 0.32512 -2.05486 180)
			(size 0.3556 1.524)
			(layers "B.Cu" "B.Mask" "B.Paste")
			(net "SMB_OCP_LAN_STBY_LVC3_SCL")
		)
		(pad "8" smd rect
			(at 0.97536 -2.05486 180)
			(size 0.3556 1.524)
			(layers "B.Cu" "B.Mask" "B.Paste")
			(net "P3V3_STBY")
		)
	)
	(footprint ""
		(layer "B.Cu")
		(at 410.464 -125.476 90)
		(property "Reference" "C2M6"
			(at 0 0 90)
			(layer "B.SilkS")
			(hide yes)
			(effects
				(font
					(size 1.27 1.27)
				)
				(justify mirror)
			)
		)
		(property "Value" ""
			(at 0 0 90)
			(layer "B.Fab")
			(effects
				(font
					(size 1.27 1.27)
				)
				(justify mirror)
			)
		)
		(duplicate_pad_numbers_are_jumpers no)
		(fp_poly
			(pts
				(xy -0.3048 -0.1016) (xy -0.3048 0.9906) (xy 0.3048 0.9906) (xy 0.3048 -0.1016)
			)
			(stroke
				(width 0)
				(type default)
			)
			(fill no)
			(layer "B.CrtYd")
		)
		(fp_line
			(start 0.3048 -0.1016)
			(end 0.3048 0.9906)
			(stroke
				(width 0.1)
				(type default)
			)
			(layer "B.Fab")
		)
		(fp_line
			(start -0.3048 -0.1016)
			(end 0.3048 -0.1016)
			(stroke
				(width 0.1)
				(type default)
			)
			(layer "B.Fab")
		)
		(fp_line
			(start 0.3048 0.9906)
			(end -0.3048 0.9906)
			(stroke
				(width 0.1)
				(type default)
			)
			(layer "B.Fab")
		)
		(fp_line
			(start -0.3048 0.9906)
			(end -0.3048 -0.1016)
			(stroke
				(width 0.1)
				(type default)
			)
			(layer "B.Fab")
		)
		(pad "1" smd rect
			(at 0 0 270)
			(size 0.508 0.508)
			(layers "B.Cu" "B.Mask" "B.Paste")
			(net "P1V05_PCH_STBY")
		)
		(pad "2" smd rect
			(at 0 0.889 270)
			(size 0.508 0.508)
			(layers "B.Cu" "B.Mask" "B.Paste")
			(net "GND")
		)
		(zone
			(layer "B.Cu")
			(hatch none 0.5)
			(connect_pads
				(clearance 0)
			)
			(min_thickness 0.25)
			(keepout
				(tracks allowed)
				(vias not_allowed)
				(pads allowed)
				(copperpour not_allowed)
				(footprints allowed)
			)
			(placement
				(enabled no)
				(sheetname "")
			)
			(fill
				(thermal_gap 0.5)
				(thermal_bridge_width 0.5)
				(island_removal_mode 0)
			)
			(polygon
				(pts
					(xy 410.718 -125.73) (xy 410.718 -125.222) (xy 411.099 -125.222) (xy 411.099 -125.73)
				)
			)
		)
		(zone
			(layer "B.Cu")
			(hatch none 0.5)
			(connect_pads
				(clearance 0)
			)
			(min_thickness 0.25)
			(keepout
				(tracks not_allowed)
				(vias allowed)
				(pads allowed)
				(copperpour not_allowed)
				(footprints allowed)
			)
			(placement
				(enabled no)
				(sheetname "")
			)
			(fill
				(thermal_gap 0.5)
				(thermal_bridge_width 0.5)
				(island_removal_mode 0)
			)
			(polygon
				(pts
					(xy 411.099 -125.73) (xy 411.099 -125.222) (xy 410.718 -125.222) (xy 410.718 -125.73)
				)
			)
		)
	)
)
